#ISCELL
  mstr_misc dns *
  *
#ISCELL
  mstr_symbols intel_corp_bpage *
  *
#ISCELL
  mstr_standard offpage *
  page236_i1
#ISCELL
  mstr_symbols gnd *
  page236_i11
#CELL
  mstr_discrete ir354xx *
  page236_i116
#CELL
  mstr_discrete ir354xx *
  page236_i117
#CELL
  mstr_discrete res *
  page236_i118
#ISCELL
  mstr_symbols gnd *
  page236_i119
#CELL
  mstr_discrete res *
  page236_i120
#ISCELL
  mstr_symbols gnd *
  page236_i121
#ISCELL
  mstr_symbols p5v_stby *
  page236_i122
#CELL
  dev_discrete cap_a *
  page236_i124
#ISCELL
  mstr_symbols gnd *
  page236_i125
#ISCELL
  mstr_symbols gnd *
  page236_i126
#CELL
  dev_discrete cap_a *
  page236_i127
#ISCELL
  mstr_symbols gnd *
  page236_i130
#ISCELL
  mstr_symbols gnd *
  page236_i133
#CELL
  mstr_discrete cap *
  page236_i134
#ISCELL
  mstr_symbols gnd *
  page236_i135
#CELL
  mstr_discrete cap *
  page236_i136
#ISCELL
  mstr_symbols gnd *
  page236_i139
#CELL
  mstr_discrete cap *
  page236_i149
#CELL
  mstr_discrete cap *
  page236_i150
#CELL
  mstr_discrete res *
  page236_i153
#CELL
  mstr_discrete res *
  page236_i154
#CELL
  w_hdl sc22u16v5mx-4-gp *
  page236_i159
#CELL
  mstr_discrete cap *
  page236_i16
#CELL
  w_hdl sc22u16v5mx-4-gp *
  page236_i160
#CELL
  w_hdl sc22u16v5mx-4-gp *
  page236_i161
#CELL
  w_hdl sc22u16v5mx-4-gp *
  page236_i162
#CELL
  w_hdl sc22u16v5mx-4-gp *
  page236_i163
#ISCELL
  mstr_symbols gnd *
  page236_i164
#CELL
  w_hdl sc22u16v5mx-4-gp *
  page236_i165
#ISCELL
  mstr_symbols gnd *
  page236_i166
#ISCELL
  mstr_symbols gnd *
  page236_i167
#ISCELL
  mstr_symbols gnd *
  page236_i168
#ISCELL
  mstr_symbols gnd *
  page236_i169
#ISCELL
  mstr_symbols gnd *
  page236_i170
#CELL
  w_hdl sc22u16v5mx-4-gp *
  page236_i171
#CELL
  w_hdl sc22u16v5mx-4-gp *
  page236_i172
#ISCELL
  mstr_symbols gnd *
  page236_i173
#ISCELL
  mstr_symbols gnd *
  page236_i174
#CELL
  mstr_discrete res *
  page236_i175
#CELL
  mstr_discrete res *
  page236_i177
#CELL
  w_hdl ind-300nh-20-gp *
  page236_i178
#CELL
  w_hdl ind-300nh-20-gp *
  page236_i179
#CELL
  w_hdl sc1u10v2kx-4-gp *
  page236_i180
#CELL
  w_hdl sc1u10v2kx-4-gp *
  page236_i181
#CELL
  w_hdl 1r3f-gp *
  page236_i182
#CELL
  w_hdl 1r3f-gp *
  page236_i183
#CELL
  mstr_discrete cap *
  page236_i19
#ISCELL
  mstr_standard offpage *
  page236_i2
#CELL
  dev_discrete cap_a *
  page236_i20
#CELL
  mstr_discrete cap *
  page236_i21
#CELL
  mstr_discrete cap *
  page236_i22
#CELL
  mstr_discrete cap *
  page236_i23
#CELL
  mstr_discrete cap *
  page236_i24
#ISCELL
  mstr_standard offpage *
  page236_i25
#CELL
  mstr_discrete cap *
  page236_i26
#ISCELL
  mstr_symbols gnd *
  page236_i27
#ISCELL
  mstr_symbols gnd *
  page236_i28
#CELL
  mstr_discrete cap *
  page236_i29
#ISCELL
  mstr_standard offpage *
  page236_i3
#ISCELL
  mstr_standard offpage *
  page236_i30
#CELL
  mstr_discrete cap *
  page236_i31
#CELL
  mstr_discrete cap *
  page236_i32
#CELL
  mstr_discrete cap *
  page236_i33
#CELL
  mstr_discrete cap *
  page236_i34
#CELL
  dev_discrete cap_a *
  page236_i35
#CELL
  mstr_discrete cap *
  page236_i36
#CELL
  mstr_discrete cap *
  page236_i39
#ISCELL
  mstr_symbols p5v_stby *
  page236_i42
#ISCELL
  mstr_symbols gnd *
  page236_i44
#CELL
  mstr_discrete cap *
  page236_i46
#ISCELL
  mstr_symbols gnd *
  page236_i47
#ISCELL
  mstr_symbols p1v05_pch_stby *
  page236_i48
#ISCELL
  mstr_standard offpage *
  page236_i52
#ISCELL
  mstr_standard offpage *
  page236_i53
#ISCELL
  mstr_standard offpage *
  page236_i54
#ISCELL
  mstr_symbols p1v05_pch_stby *
  page236_i55
#CELL
  mstr_discrete res *
  page236_i56
#CELL
  mstr_discrete res *
  page236_i57
#ISCELL
  mstr_symbols gnd *
  page236_i58
#CELL
  mstr_discrete res *
  page236_i59
#ISCELL
  mstr_standard offpage *
  page236_i60
#ISCELL
  mstr_standard offpage *
  page236_i61
#ISCELL
  mstr_symbols pvnn_pch_stby *
  page236_i7
#CELL
  mstr_discrete capp *
  page236_i71
#CELL
  mstr_discrete capp *
  page236_i73
#CELL
  mstr_discrete capp *
  page236_i74
#CELL
  mstr_discrete capp *
  page236_i75
#CELL
  mstr_discrete capp *
  page236_i76
#CELL
  mstr_discrete capp *
  page236_i77
#CELL
  mstr_discrete capp *
  page236_i78
#CELL
  mstr_discrete capp *
  page236_i79
#ISCELL
  mstr_symbols gnd *
  page236_i8
#ISCELL
  mstr_symbols gnd *
  page236_i82
#ISCELL
  mstr_standard offpage *
  page236_i85
#ISCELL
  mstr_standard offpage *
  page236_i86
#ISCELL
  mstr_symbols pvnn_pch_stby *
  page236_i87
#ISCELL
  mstr_standard offpage *
  page236_i88
#ISCELL
  mstr_standard offpage *
  page236_i89
#CELL
  mstr_discrete cap *
  page236_i9
#CELL
  mstr_discrete res *
  page236_i90
#CELL
  mstr_discrete res *
  page236_i92
#CELL
  mstr_discrete res *
  page236_i93
#CELL
  mstr_discrete res *
  page236_i94
#ISCELL
  mstr_symbols vcc_core *
  page236_i95
#ISCELL
  mstr_symbols vcc_core *
  page236_i96
#ISCELL
  mstr_symbols vcc_core *
  page236_i97
